FILE_TYPE = MACRO_DRAWING;
SET COLOR_WIRE YELLOW;
SET COLOR_PROP MONO;
SET COLOR_DOT WHITE;
SET COLOR_ARC YELLOW;
SET COLOR_BODY GREEN;
SET COLOR_NOTE MONO;
SET PROP_DISPLAY VALUE;
SET PAGE_NUMBER P160;
FORCEADD OFFPAGE..2
(-2175 4425);
FORCEPROP 2 LAST $XR0 108 
J 0
(-1986 4425);
DISPLAY 0.638298 (-1986 4425);
PAINT MONO (-1986 4425);
FORCEPROP 2 LAST CDS_LIB mstr_standard
J 0
(-2175 4425);
PAINT ORANGE (-2175 4425);
DISPLAY INVISIBLE (-2175 4425);
FORCEPROP 2 LAST PATH I1
J 0
(-2000 4500);
DISPLAY 1.021277 (-2000 4500);
PAINT ORANGE (-2000 4500);
DISPLAY INVISIBLE (-2000 4500);
FORCEPROP 1 LAST OFFPAGE TRUE
J 0
(-1850 4300);
DISPLAY 0.872340 (-1850 4300);
PAINT GREEN (-1850 4300);
DISPLAY INVISIBLE (-1850 4300);
FORCEPROP 1 LAST COMMENT_BODY TRUE
J 0
(-2220 4330);
DISPLAY 0.872340 (-2220 4330);
PAINT GREEN (-2220 4330);
DISPLAY INVISIBLE (-2220 4330);
FORCEADD OFFPAGE..3
(-2175 3700);
FORCEPROP 2 LAST $XR2 182 
J 0
(-1721 3700);
DISPLAY 0.638298 (-1721 3700);
PAINT MONO (-1721 3700);
FORCEPROP 2 LAST $XR1 156 
J 0
(-1841 3700);
DISPLAY 0.638298 (-1841 3700);
PAINT MONO (-1841 3700);
FORCEPROP 2 LAST $XR0 138 
J 0
(-1961 3700);
DISPLAY 0.638298 (-1961 3700);
PAINT MONO (-1961 3700);
FORCEPROP 2 LAST CDS_LIB mstr_standard
J 0
(-2175 3700);
PAINT ORANGE (-2175 3700);
DISPLAY INVISIBLE (-2175 3700);
FORCEPROP 2 LAST PATH I10
J 0
(-1700 3750);
DISPLAY 1.021277 (-1700 3750);
PAINT ORANGE (-1700 3750);
DISPLAY INVISIBLE (-1700 3750);
FORCEPROP 1 LAST OFFPAGE TRUE
J 0
(-1850 3575);
DISPLAY 0.872340 (-1850 3575);
PAINT GREEN (-1850 3575);
DISPLAY INVISIBLE (-1850 3575);
FORCEPROP 1 LAST COMMENT_BODY TRUE
J 0
(-2225 3600);
DISPLAY 0.872340 (-2225 3600);
PAINT GREEN (-2225 3600);
DISPLAY INVISIBLE (-2225 3600);
FORCEADD OFFPAGE..4
R 2
(-4700 4425);
FORCEPROP 2 LAST $XR0 144 
J 0
(-4952 4425);
DISPLAY 0.638298 (-4952 4425);
PAINT MONO (-4952 4425);
FORCEPROP 2 LAST CDS_LIB mstr_standard
J 0
(-4700 4425);
PAINT ORANGE (-4700 4425);
DISPLAY INVISIBLE (-4700 4425);
FORCEPROP 2 LAST PATH I17
J 0
(-4650 4500);
DISPLAY 1.021277 (-4650 4500);
PAINT ORANGE (-4650 4500);
DISPLAY INVISIBLE (-4650 4500);
FORCEPROP 1 LAST OFFPAGE TRUE
J 2
(-5025 4300);
DISPLAY 0.872340 (-5025 4300);
PAINT GREEN (-5025 4300);
DISPLAY INVISIBLE (-5025 4300);
FORCEPROP 1 LAST COMMENT_BODY TRUE
J 2
(-4675 4325);
DISPLAY 0.872340 (-4675 4325);
PAINT GREEN (-4675 4325);
DISPLAY INVISIBLE (-4675 4325);
FORCEADD OFFPAGE..3
R 2
(-4700 4600);
FORCEPROP 2 LAST $XR0 144 
J 0
(-4980 4600);
DISPLAY 0.638298 (-4980 4600);
PAINT MONO (-4980 4600);
FORCEPROP 2 LAST CDS_LIB mstr_standard
J 0
(-4700 4600);
PAINT ORANGE (-4700 4600);
DISPLAY INVISIBLE (-4700 4600);
FORCEPROP 2 LAST PATH I18
J 0
(-4975 4650);
DISPLAY 1.021277 (-4975 4650);
PAINT ORANGE (-4975 4650);
DISPLAY INVISIBLE (-4975 4650);
FORCEPROP 1 LAST OFFPAGE TRUE
J 2
(-5025 4475);
PAINT GREEN (-5025 4475);
DISPLAY INVISIBLE (-5025 4475);
FORCEPROP 1 LAST COMMENT_BODY TRUE
J 2
(-4650 4500);
DISPLAY 1.170213 (-4650 4500);
PAINT GREEN (-4650 4500);
DISPLAY INVISIBLE (-4650 4500);
FORCEADD OFFPAGE..3
R 2
(-4650 3700);
FORCEPROP 2 LAST $XR0 144 
J 0
(-4930 3700);
DISPLAY 0.638298 (-4930 3700);
PAINT MONO (-4930 3700);
FORCEPROP 2 LAST CDS_LIB mstr_standard
J 0
(-4650 3700);
PAINT ORANGE (-4650 3700);
DISPLAY INVISIBLE (-4650 3700);
FORCEPROP 2 LAST PATH I19
J 0
(-4925 3750);
DISPLAY 1.021277 (-4925 3750);
PAINT ORANGE (-4925 3750);
DISPLAY INVISIBLE (-4925 3750);
FORCEPROP 1 LAST OFFPAGE TRUE
J 2
(-4975 3575);
PAINT GREEN (-4975 3575);
DISPLAY INVISIBLE (-4975 3575);
FORCEPROP 1 LAST COMMENT_BODY TRUE
J 2
(-4600 3600);
DISPLAY 1.170213 (-4600 3600);
PAINT GREEN (-4600 3600);
DISPLAY INVISIBLE (-4600 3600);
FORCEADD OFFPAGE..3
(-2175 4600);
FORCEPROP 2 LAST $XR0 108 
J 0
(-1961 4600);
DISPLAY 0.638298 (-1961 4600);
PAINT MONO (-1961 4600);
FORCEPROP 2 LAST CDS_LIB mstr_standard
J 0
(-2175 4600);
PAINT ORANGE (-2175 4600);
DISPLAY INVISIBLE (-2175 4600);
FORCEPROP 2 LAST PATH I2
J 0
(-1700 4650);
DISPLAY 1.021277 (-1700 4650);
PAINT ORANGE (-1700 4650);
DISPLAY INVISIBLE (-1700 4650);
FORCEPROP 1 LAST OFFPAGE TRUE
J 0
(-1850 4475);
DISPLAY 0.872340 (-1850 4475);
PAINT GREEN (-1850 4475);
DISPLAY INVISIBLE (-1850 4475);
FORCEPROP 1 LAST COMMENT_BODY TRUE
J 0
(-2225 4500);
DISPLAY 0.872340 (-2225 4500);
PAINT GREEN (-2225 4500);
DISPLAY INVISIBLE (-2225 4500);
FORCEADD OFFPAGE..4
R 2
(-4675 3525);
FORCEPROP 2 LAST $XR0 144 
J 0
(-4957 3525);
DISPLAY 0.638298 (-4957 3525);
PAINT MONO (-4957 3525);
FORCEPROP 2 LAST CDS_LIB mstr_standard
J 0
(-4675 3525);
PAINT ORANGE (-4675 3525);
DISPLAY INVISIBLE (-4675 3525);
FORCEPROP 2 LAST PATH I20
J 0
(-4625 3600);
DISPLAY 1.021277 (-4625 3600);
PAINT ORANGE (-4625 3600);
DISPLAY INVISIBLE (-4625 3600);
FORCEPROP 1 LAST OFFPAGE TRUE
J 2
(-5000 3400);
DISPLAY 0.872340 (-5000 3400);
PAINT GREEN (-5000 3400);
DISPLAY INVISIBLE (-5000 3400);
FORCEPROP 1 LAST COMMENT_BODY TRUE
J 2
(-4650 3425);
DISPLAY 0.872340 (-4650 3425);
PAINT GREEN (-4650 3425);
DISPLAY INVISIBLE (-4650 3425);
FORCEADD RES..1
(-3350 4600);
FORCEPROP 1 LAST TOLERANCE 1%
J 0
(-3225 4600);
DISPLAY 0.617021 (-3225 4600);
PAINT SKYBLUE (-3225 4600);
FORCEPROP 1 LAST MATERIAL CHIP
J 0
(-3550 4600);
DISPLAY 0.617021 (-3550 4600);
PAINT SKYBLUE (-3550 4600);
FORCEPROP 1 LAST LOCATION R1T8
J 0
(-3550 4650);
DISPLAY 0.617021 (-3550 4650);
PAINT AQUA (-3550 4650);
FORCEPROP 1 LAST VALUE 20.0
J 2
(-3050 4600);
DISPLAY 0.617021 (-3050 4600);
PAINT SKYBLUE (-3050 4600);
FORCEPROP 1 LASTPIN (-3250 4600) $PN 2
J 0
(-3288 4612);
DISPLAY 0.617021 (-3288 4612);
PAINT MONO (-3288 4612);
FORCEPROP 1 LASTPIN (-3450 4600) $PN 1
J 0
(-3438 4612);
DISPLAY 0.617021 (-3438 4612);
PAINT MONO (-3438 4612);
FORCEPROP 1 LAST WATTAGE 1/16W
J 0
(-3150 4650);
DISPLAY 0.638298 (-3150 4650);
PAINT SKYBLUE (-3150 4650);
FORCEPROP 1 LAST PACK_TYPE 0402
J 0
(-3000 4650);
DISPLAY 0.638298 (-3000 4650);
PAINT SKYBLUE (-3000 4650);
FORCEPROP 1 LAST PART_NUMBER G21796-173
J 0
(-3400 4650);
DISPLAY 0.638298 (-3400 4650);
PAINT BLUE (-3400 4650);
FORCEPROP 2 LAST BOM_COST SM_CONTROLLER
J 0
(-3400 4750);
DISPLAY 1.021277 (-3400 4750);
PAINT ORANGE (-3400 4750);
DISPLAY INVISIBLE (-3400 4750);
FORCEPROP 2 LAST CDS_LIB mstr_discrete
J 0
(-3350 4600);
PAINT ORANGE (-3350 4600);
DISPLAY INVISIBLE (-3350 4600);
FORCEPROP 2 LAST CDS_SEC 1
J 0
(-3400 4800);
DISPLAY 1.404255 (-3400 4800);
PAINT ORANGE (-3400 4800);
DISPLAY INVISIBLE (-3400 4800);
FORCEPROP 2 LAST $SEC 1
J 0
(-3400 4800);
DISPLAY 0.936170 (-3400 4800);
PAINT MONO (-3400 4800);
DISPLAY INVISIBLE (-3400 4800);
FORCEPROP 2 LAST CDS_LOCATION R1T8
J 0
(-3400 4650);
DISPLAY 0.617021 (-3400 4650);
PAINT AQUA (-3400 4650);
DISPLAY INVISIBLE (-3400 4650);
FORCEPROP 1 LAST PATH I4
J 0
(-3400 4750);
DISPLAY 0.978723 (-3400 4750);
PAINT WHITE (-3400 4750);
DISPLAY INVISIBLE (-3400 4750);
FORCEPROP 2 LAST ROOM SMBUS
J 0
(-3400 4700);
DISPLAY 1.021277 (-3400 4700);
PAINT ORANGE (-3400 4700);
DISPLAY INVISIBLE (-3400 4700);
FORCEADD RES..2
(-4000 4975);
FORCEPROP 1 LAST WATTAGE 1/16W
J 0
(-3960 4950);
DISPLAY 0.617021 (-3960 4950);
PAINT SKYBLUE (-3960 4950);
FORCEPROP 1 LAST LOCATION R1T3
J 0
(-3955 5100);
DISPLAY 0.617021 (-3955 5100);
PAINT AQUA (-3955 5100);
FORCEPROP 1 LAST VALUE 665
J 0
(-3955 5050);
DISPLAY 0.617021 (-3955 5050);
PAINT SKYBLUE (-3955 5050);
FORCEPROP 1 LAST MATERIAL CHIP
J 0
(-3960 4900);
DISPLAY 0.617021 (-3960 4900);
PAINT SKYBLUE (-3960 4900);
FORCEPROP 1 LASTPIN (-4000 5075) $PN 1
J 0
(-3995 5037);
DISPLAY 0.787234 (-3995 5037);
PAINT ORANGE (-3995 5037);
FORCEPROP 1 LASTPIN (-4000 4875) $PN 2
J 0
(-3995 4885);
DISPLAY 0.787234 (-3995 4885);
PAINT ORANGE (-3995 4885);
FORCEPROP 1 LAST PACK_TYPE 0402
J 0
(-3960 4800);
DISPLAY 0.617021 (-3960 4800);
PAINT SKYBLUE (-3960 4800);
FORCEPROP 1 LAST PART_NUMBER G21796-235
J 0
(-3960 4850);
DISPLAY 0.617021 (-3960 4850);
PAINT BLUE (-3960 4850);
FORCEPROP 1 LAST TOLERANCE 1.0%
J 0
(-3955 5000);
DISPLAY 0.617021 (-3955 5000);
PAINT SKYBLUE (-3955 5000);
FORCEPROP 0 LAST SKU B
J 0
(-3950 5200);
DISPLAY 1.021277 (-3950 5200);
PAINT ORANGE (-3950 5200);
DISPLAY INVISIBLE (-3950 5200);
FORCEPROP 0 LAST BOM_COST SM_CONTROLLER
J 0
(-3950 5300);
DISPLAY 1.021277 (-3950 5300);
PAINT ORANGE (-3950 5300);
DISPLAY INVISIBLE (-3950 5300);
FORCEPROP 2 LAST CDS_LIB mstr_discrete
J 0
(-4000 4975);
PAINT ORANGE (-4000 4975);
DISPLAY INVISIBLE (-4000 4975);
FORCEPROP 2 LAST CDS_LOCATION R1T3
J 0
(-3955 5100);
DISPLAY 0.617021 (-3955 5100);
PAINT AQUA (-3955 5100);
DISPLAY INVISIBLE (-3955 5100);
FORCEPROP 1 LAST PATH I46
J 0
(-3950 5150);
DISPLAY 0.978723 (-3950 5150);
PAINT WHITE (-3950 5150);
DISPLAY INVISIBLE (-3950 5150);
FORCEPROP 0 LAST ROOM SMBUS
J 0
(-3950 5200);
DISPLAY 1.021277 (-3950 5200);
PAINT ORANGE (-3950 5200);
DISPLAY INVISIBLE (-3950 5200);
FORCEPROP 2 LAST SEC 1
J 0
(-3950 5200);
PAINT MONO (-3950 5200);
DISPLAY INVISIBLE (-3950 5200);
FORCEPROP 2 LAST SEC_TYPE 0402
J 0
(-3950 5200);
DISPLAY 1.021277 (-3950 5200);
PAINT ORANGE (-3950 5200);
DISPLAY INVISIBLE (-3950 5200);
FORCEADD P3V3_STBY..1
(-3650 5275);
FORCEPROP 3 LASTPIN (-3650 5225) SIG_NAME P3V3_STBY\g
J 0
(-3640 5235);
DISPLAY 0.659574 (-3640 5235);
PAINT MONO (-3640 5235);
DISPLAY INVISIBLE (-3640 5235);
FORCEPROP 1 LAST VOLTAGE 3.3V
J 0
(-3695 5232);
DISPLAY 0.340426 (-3695 5232);
PAINT SKYBLUE (-3695 5232);
DISPLAY INVISIBLE (-3695 5232);
FORCEPROP 2 LAST CDS_LIB mstr_symbols
J 0
(-3650 5275);
PAINT MONO (-3650 5275);
DISPLAY INVISIBLE (-3650 5275);
FORCEPROP 1 LAST SIZE 1B
J 0
(-3605 5297);
DISPLAY 0.340426 (-3605 5297);
PAINT GREEN (-3605 5297);
DISPLAY INVISIBLE (-3605 5297);
FORCEPROP 1 LAST PATH I47
J 0
(-3605 5277);
DISPLAY 0.340426 (-3605 5277);
PAINT GREEN (-3605 5277);
DISPLAY INVISIBLE (-3605 5277);
FORCEPROP 1 LAST BODY_TYPE PLUMBING
J 0
(-3695 5232);
DISPLAY 0.340426 (-3695 5232);
PAINT GREEN (-3695 5232);
DISPLAY INVISIBLE (-3695 5232);
FORCEPROP 1 LAST HDL_POWER P3V3_STBY
J 0
(-3950 5150);
DISPLAY 0.872340 (-3950 5150);
PAINT ORANGE (-3950 5150);
DISPLAY INVISIBLE (-3950 5150);
FORCEADD P3V3_STBY..1
(-4000 5275);
FORCEPROP 3 LASTPIN (-4000 5225) SIG_NAME P3V3_STBY\g
J 0
(-3990 5235);
DISPLAY 0.659574 (-3990 5235);
PAINT MONO (-3990 5235);
DISPLAY INVISIBLE (-3990 5235);
FORCEPROP 1 LAST VOLTAGE 3.3V
J 0
(-4045 5232);
DISPLAY 0.340426 (-4045 5232);
PAINT SKYBLUE (-4045 5232);
DISPLAY INVISIBLE (-4045 5232);
FORCEPROP 2 LAST CDS_LIB mstr_symbols
J 0
(-4000 5275);
PAINT MONO (-4000 5275);
DISPLAY INVISIBLE (-4000 5275);
FORCEPROP 1 LAST SIZE 1B
J 0
(-3955 5297);
DISPLAY 0.340426 (-3955 5297);
PAINT GREEN (-3955 5297);
DISPLAY INVISIBLE (-3955 5297);
FORCEPROP 1 LAST PATH I48
J 0
(-3955 5277);
DISPLAY 0.340426 (-3955 5277);
PAINT GREEN (-3955 5277);
DISPLAY INVISIBLE (-3955 5277);
FORCEPROP 1 LAST BODY_TYPE PLUMBING
J 0
(-4045 5232);
DISPLAY 0.340426 (-4045 5232);
PAINT GREEN (-4045 5232);
DISPLAY INVISIBLE (-4045 5232);
FORCEPROP 1 LAST HDL_POWER P3V3_STBY
J 0
(-4300 5150);
DISPLAY 0.872340 (-4300 5150);
PAINT ORANGE (-4300 5150);
DISPLAY INVISIBLE (-4300 5150);
FORCEADD RES..2
(-3650 4975);
FORCEPROP 1 LAST LOCATION R1T2
J 0
(-3605 5100);
DISPLAY 0.617021 (-3605 5100);
PAINT AQUA (-3605 5100);
FORCEPROP 1 LAST VALUE 665
J 0
(-3605 5050);
DISPLAY 0.617021 (-3605 5050);
PAINT SKYBLUE (-3605 5050);
FORCEPROP 1 LAST MATERIAL CHIP
J 0
(-3610 4900);
DISPLAY 0.617021 (-3610 4900);
PAINT SKYBLUE (-3610 4900);
FORCEPROP 1 LAST WATTAGE 1/16W
J 0
(-3610 4950);
DISPLAY 0.617021 (-3610 4950);
PAINT SKYBLUE (-3610 4950);
FORCEPROP 1 LAST PACK_TYPE 0402
J 0
(-3610 4800);
DISPLAY 0.617021 (-3610 4800);
PAINT SKYBLUE (-3610 4800);
FORCEPROP 1 LASTPIN (-3650 5075) $PN 1
J 0
(-3645 5037);
DISPLAY 0.787234 (-3645 5037);
PAINT ORANGE (-3645 5037);
FORCEPROP 1 LASTPIN (-3650 4875) $PN 2
J 0
(-3645 4885);
DISPLAY 0.787234 (-3645 4885);
PAINT ORANGE (-3645 4885);
FORCEPROP 1 LAST TOLERANCE 1.0%
J 0
(-3605 5000);
DISPLAY 0.617021 (-3605 5000);
PAINT SKYBLUE (-3605 5000);
FORCEPROP 1 LAST PART_NUMBER G21796-235
J 0
(-3610 4850);
DISPLAY 0.617021 (-3610 4850);
PAINT BLUE (-3610 4850);
FORCEPROP 0 LAST SKU B
J 0
(-3600 5200);
DISPLAY 1.021277 (-3600 5200);
PAINT ORANGE (-3600 5200);
DISPLAY INVISIBLE (-3600 5200);
FORCEPROP 0 LAST BOM_COST SM_CONTROLLER
J 0
(-3600 5300);
DISPLAY 1.021277 (-3600 5300);
PAINT ORANGE (-3600 5300);
DISPLAY INVISIBLE (-3600 5300);
FORCEPROP 2 LAST CDS_LIB mstr_discrete
J 0
(-3650 4975);
PAINT ORANGE (-3650 4975);
DISPLAY INVISIBLE (-3650 4975);
FORCEPROP 2 LAST CDS_LOCATION R1T2
J 0
(-3605 5100);
DISPLAY 0.617021 (-3605 5100);
PAINT AQUA (-3605 5100);
DISPLAY INVISIBLE (-3605 5100);
FORCEPROP 1 LAST PATH I49
J 0
(-3600 5150);
DISPLAY 0.978723 (-3600 5150);
PAINT WHITE (-3600 5150);
DISPLAY INVISIBLE (-3600 5150);
FORCEPROP 0 LAST ROOM SMBUS
J 0
(-3600 5200);
DISPLAY 1.021277 (-3600 5200);
PAINT ORANGE (-3600 5200);
DISPLAY INVISIBLE (-3600 5200);
FORCEPROP 2 LAST SEC 1
J 0
(-3600 5200);
PAINT MONO (-3600 5200);
DISPLAY INVISIBLE (-3600 5200);
FORCEPROP 2 LAST SEC_TYPE 0402
J 0
(-3600 5200);
DISPLAY 1.021277 (-3600 5200);
PAINT ORANGE (-3600 5200);
DISPLAY INVISIBLE (-3600 5200);
FORCEADD RES..1
(-3350 4425);
FORCEPROP 1 LAST TOLERANCE 1%
J 0
(-3225 4425);
DISPLAY 0.617021 (-3225 4425);
PAINT SKYBLUE (-3225 4425);
FORCEPROP 1 LAST MATERIAL CHIP
J 0
(-3550 4425);
DISPLAY 0.617021 (-3550 4425);
PAINT SKYBLUE (-3550 4425);
FORCEPROP 1 LAST LOCATION R1T7
J 0
(-3550 4475);
DISPLAY 0.617021 (-3550 4475);
PAINT AQUA (-3550 4475);
FORCEPROP 1 LASTPIN (-3450 4425) $PN 1
J 0
(-3438 4437);
DISPLAY 0.617021 (-3438 4437);
PAINT MONO (-3438 4437);
FORCEPROP 1 LAST WATTAGE 1/16W
J 0
(-3150 4475);
DISPLAY 0.638298 (-3150 4475);
PAINT SKYBLUE (-3150 4475);
FORCEPROP 1 LAST VALUE 20.0
J 2
(-3050 4425);
DISPLAY 0.617021 (-3050 4425);
PAINT SKYBLUE (-3050 4425);
FORCEPROP 1 LAST PACK_TYPE 0402
J 0
(-3000 4475);
DISPLAY 0.638298 (-3000 4475);
PAINT SKYBLUE (-3000 4475);
FORCEPROP 1 LASTPIN (-3250 4425) $PN 2
J 0
(-3288 4437);
DISPLAY 0.617021 (-3288 4437);
PAINT MONO (-3288 4437);
FORCEPROP 1 LAST PART_NUMBER G21796-173
J 0
(-3400 4475);
DISPLAY 0.638298 (-3400 4475);
PAINT BLUE (-3400 4475);
FORCEPROP 2 LAST BOM_COST SM_CONTROLLER
J 0
(-3400 4575);
DISPLAY 1.021277 (-3400 4575);
PAINT ORANGE (-3400 4575);
DISPLAY INVISIBLE (-3400 4575);
FORCEPROP 2 LAST CDS_LIB mstr_discrete
J 0
(-3350 4425);
PAINT ORANGE (-3350 4425);
DISPLAY INVISIBLE (-3350 4425);
FORCEPROP 2 LAST CDS_SEC 1
J 0
(-3400 4625);
DISPLAY 1.404255 (-3400 4625);
PAINT ORANGE (-3400 4625);
DISPLAY INVISIBLE (-3400 4625);
FORCEPROP 2 LAST $SEC 1
J 0
(-3400 4625);
DISPLAY 0.936170 (-3400 4625);
PAINT MONO (-3400 4625);
DISPLAY INVISIBLE (-3400 4625);
FORCEPROP 2 LAST CDS_LOCATION R1T7
J 0
(-3400 4475);
DISPLAY 0.617021 (-3400 4475);
PAINT AQUA (-3400 4475);
DISPLAY INVISIBLE (-3400 4475);
FORCEPROP 1 LAST PATH I50
J 0
(-3400 4575);
DISPLAY 0.978723 (-3400 4575);
PAINT WHITE (-3400 4575);
DISPLAY INVISIBLE (-3400 4575);
FORCEPROP 2 LAST ROOM SMBUS
J 0
(-3400 4525);
DISPLAY 1.021277 (-3400 4525);
PAINT ORANGE (-3400 4525);
DISPLAY INVISIBLE (-3400 4525);
FORCEADD RES..1
(-3350 3700);
FORCEPROP 1 LAST TOLERANCE 1%
J 0
(-3225 3700);
DISPLAY 0.617021 (-3225 3700);
PAINT SKYBLUE (-3225 3700);
FORCEPROP 1 LASTPIN (-3250 3700) $PN 2
J 0
(-3288 3712);
DISPLAY 0.617021 (-3288 3712);
PAINT MONO (-3288 3712);
FORCEPROP 1 LASTPIN (-3450 3700) $PN 1
J 0
(-3438 3712);
DISPLAY 0.617021 (-3438 3712);
PAINT MONO (-3438 3712);
FORCEPROP 1 LAST WATTAGE 1/16W
J 0
(-3150 3750);
DISPLAY 0.638298 (-3150 3750);
PAINT SKYBLUE (-3150 3750);
FORCEPROP 1 LAST VALUE 20.0
J 2
(-3050 3700);
DISPLAY 0.617021 (-3050 3700);
PAINT SKYBLUE (-3050 3700);
FORCEPROP 1 LAST MATERIAL CHIP
J 0
(-3550 3700);
DISPLAY 0.617021 (-3550 3700);
PAINT SKYBLUE (-3550 3700);
FORCEPROP 1 LAST LOCATION R9F23
J 0
(-3550 3750);
DISPLAY 0.617021 (-3550 3750);
PAINT AQUA (-3550 3750);
FORCEPROP 1 LAST PART_NUMBER G21796-173
J 0
(-3400 3750);
DISPLAY 0.638298 (-3400 3750);
PAINT BLUE (-3400 3750);
FORCEPROP 1 LAST PACK_TYPE 0402
J 0
(-3000 3750);
DISPLAY 0.638298 (-3000 3750);
PAINT SKYBLUE (-3000 3750);
FORCEPROP 2 LAST BOM_COST SM_CONTROLLER
J 0
(-3400 3850);
DISPLAY 1.021277 (-3400 3850);
PAINT ORANGE (-3400 3850);
DISPLAY INVISIBLE (-3400 3850);
FORCEPROP 2 LAST CDS_LIB mstr_discrete
J 0
(-3350 3700);
PAINT ORANGE (-3350 3700);
DISPLAY INVISIBLE (-3350 3700);
FORCEPROP 2 LAST CDS_SEC 1
J 0
(-3400 3900);
DISPLAY 1.404255 (-3400 3900);
PAINT ORANGE (-3400 3900);
DISPLAY INVISIBLE (-3400 3900);
FORCEPROP 2 LAST $SEC 1
J 0
(-3400 3900);
DISPLAY 0.936170 (-3400 3900);
PAINT MONO (-3400 3900);
DISPLAY INVISIBLE (-3400 3900);
FORCEPROP 2 LAST CDS_LOCATION R9F23
J 0
(-3400 3750);
DISPLAY 0.617021 (-3400 3750);
PAINT AQUA (-3400 3750);
DISPLAY INVISIBLE (-3400 3750);
FORCEPROP 1 LAST PATH I51
J 0
(-3400 3850);
DISPLAY 0.978723 (-3400 3850);
PAINT WHITE (-3400 3850);
DISPLAY INVISIBLE (-3400 3850);
FORCEPROP 2 LAST ROOM SMBUS
J 0
(-3400 3800);
DISPLAY 1.021277 (-3400 3800);
PAINT ORANGE (-3400 3800);
DISPLAY INVISIBLE (-3400 3800);
FORCEADD RES..1
(-3350 3525);
FORCEPROP 1 LAST MATERIAL CHIP
J 0
(-3550 3525);
DISPLAY 0.617021 (-3550 3525);
PAINT SKYBLUE (-3550 3525);
FORCEPROP 1 LASTPIN (-3450 3525) $PN 1
J 0
(-3438 3537);
DISPLAY 0.617021 (-3438 3537);
PAINT MONO (-3438 3537);
FORCEPROP 1 LAST LOCATION R9F22
J 0
(-3550 3575);
DISPLAY 0.617021 (-3550 3575);
PAINT AQUA (-3550 3575);
FORCEPROP 1 LASTPIN (-3250 3525) $PN 2
J 0
(-3288 3537);
DISPLAY 0.617021 (-3288 3537);
PAINT MONO (-3288 3537);
FORCEPROP 1 LAST PART_NUMBER G21796-173
J 0
(-3400 3575);
DISPLAY 0.638298 (-3400 3575);
PAINT BLUE (-3400 3575);
FORCEPROP 1 LAST TOLERANCE 1%
J 0
(-3225 3525);
DISPLAY 0.617021 (-3225 3525);
PAINT SKYBLUE (-3225 3525);
FORCEPROP 1 LAST VALUE 20.0
J 2
(-3050 3525);
DISPLAY 0.617021 (-3050 3525);
PAINT SKYBLUE (-3050 3525);
FORCEPROP 1 LAST WATTAGE 1/16W
J 0
(-3150 3575);
DISPLAY 0.638298 (-3150 3575);
PAINT SKYBLUE (-3150 3575);
FORCEPROP 1 LAST PACK_TYPE 0402
J 0
(-3000 3575);
DISPLAY 0.638298 (-3000 3575);
PAINT SKYBLUE (-3000 3575);
FORCEPROP 2 LAST BOM_COST SM_CONTROLLER
J 0
(-3400 3675);
DISPLAY 1.021277 (-3400 3675);
PAINT ORANGE (-3400 3675);
DISPLAY INVISIBLE (-3400 3675);
FORCEPROP 2 LAST CDS_LIB mstr_discrete
J 0
(-3350 3525);
PAINT ORANGE (-3350 3525);
DISPLAY INVISIBLE (-3350 3525);
FORCEPROP 2 LAST CDS_SEC 1
J 0
(-3400 3725);
DISPLAY 1.404255 (-3400 3725);
PAINT ORANGE (-3400 3725);
DISPLAY INVISIBLE (-3400 3725);
FORCEPROP 2 LAST $SEC 1
J 0
(-3400 3725);
DISPLAY 0.936170 (-3400 3725);
PAINT MONO (-3400 3725);
DISPLAY INVISIBLE (-3400 3725);
FORCEPROP 2 LAST CDS_LOCATION R9F22
J 0
(-3400 3575);
DISPLAY 0.617021 (-3400 3575);
PAINT AQUA (-3400 3575);
DISPLAY INVISIBLE (-3400 3575);
FORCEPROP 1 LAST PATH I52
J 0
(-3400 3675);
DISPLAY 0.978723 (-3400 3675);
PAINT WHITE (-3400 3675);
DISPLAY INVISIBLE (-3400 3675);
FORCEPROP 2 LAST ROOM SMBUS
J 0
(-3400 3625);
DISPLAY 1.021277 (-3400 3625);
PAINT ORANGE (-3400 3625);
DISPLAY INVISIBLE (-3400 3625);
FORCEADD OFFPAGE..2
(-2175 3525);
FORCEPROP 2 LAST $XR2 182 
J 0
(-1746 3525);
DISPLAY 0.638298 (-1746 3525);
PAINT MONO (-1746 3525);
FORCEPROP 2 LAST $XR1 156 
J 0
(-1866 3525);
DISPLAY 0.638298 (-1866 3525);
PAINT MONO (-1866 3525);
FORCEPROP 2 LAST $XR0 138 
J 0
(-1986 3525);
DISPLAY 0.638298 (-1986 3525);
PAINT MONO (-1986 3525);
FORCEPROP 2 LAST CDS_LIB mstr_standard
J 0
(-2175 3525);
PAINT ORANGE (-2175 3525);
DISPLAY INVISIBLE (-2175 3525);
FORCEPROP 2 LAST PATH I9
J 0
(-2000 3600);
DISPLAY 1.021277 (-2000 3600);
PAINT ORANGE (-2000 3600);
DISPLAY INVISIBLE (-2000 3600);
FORCEPROP 1 LAST OFFPAGE TRUE
J 0
(-1850 3400);
DISPLAY 0.872340 (-1850 3400);
PAINT GREEN (-1850 3400);
DISPLAY INVISIBLE (-1850 3400);
FORCEPROP 1 LAST COMMENT_BODY TRUE
J 0
(-2220 3430);
DISPLAY 0.872340 (-2220 3430);
PAINT GREEN (-2220 3430);
DISPLAY INVISIBLE (-2220 3430);
FORCEADD CAD_NOTE..1
(-3425 3350);
FORCEPROP 0 LAST L1 PLACE RESISTORS CLOSE TO BMC
J 0
(-4100 3200);
DISPLAY 1.021277 (-4100 3200);
PAINT ORANGE (-4100 3200);
FORCEPROP 2 LAST CDS_LIB mstr_symbols
J 0
(-3425 3350);
PAINT ORANGE (-3425 3350);
DISPLAY INVISIBLE (-3425 3350);
FORCEPROP 1 LAST COMMENT_BODY TRUE
J 0
(-3400 3450);
DISPLAY 0.978723 (-3400 3450);
PAINT ORANGE (-3400 3450);
DISPLAY INVISIBLE (-3400 3450);
FORCEADD INTEL_CORP_BPAGE..1
(2600 525);
FORCEPROP 1 LAST CDS_CON_LAST_MODIFIED Fri Jun 16 17:49:00 2017
J 0
(1175 850);
DISPLAY 1.361702 (1175 850);
PAINT GREEN (1175 850);
DISPLAY INVISIBLE (1175 850);
FORCEPROP 1 LAST CUSTOM_TXT_CDS <CURRENT_DESIGN_SHEET> OF <TOTAL_DESIGN_SHEETS>
J 0
(2100 550);
PAINT ORANGE (2100 550);
FORCEPROP 1 LAST CUSTOM_TXT_CDS <CON_LAST_MODIFIED>
J 0
(-1400 625);
PAINT ORANGE (-1400 625);
FORCEPROP 2 LAST CUSTOM_TXT_CDS <XR_PAGE_TITLE>
J 0
(-5290 5775);
DISPLAY 0.638298 (-5290 5775);
PAINT PINK (-5290 5775);
DISPLAY INVISIBLE (-5290 5775);
FORCEPROP 1 LAST SCH_TITLE SMBUS PULLUPS (2 OF 2)
J 0
(-5350 575);
DISPLAY 1.212766 (-5350 575);
PAINT ORANGE (-5350 575);
FORCEPROP 2 LAST PAGE_BORDER TRUE
J 0
(-5290 5775);
DISPLAY 0.851064 (-5290 5775);
PAINT PINK (-5290 5775);
DISPLAY INVISIBLE (-5290 5775);
FORCEPROP 2 LAST CDS_LIB mstr_symbols
J 0
(2600 525);
PAINT MONO (2600 525);
DISPLAY INVISIBLE (2600 525);
FORCEPROP 1 LAST COMMENT_BODY TRUE
J 0
(2612 537);
DISPLAY 0.617021 (2612 537);
PAINT GREEN (2612 537);
DISPLAY INVISIBLE (2612 537);
FORCEPROP 2 LAST CDS_XR_PAGE_TITLE CR-160 : @BASEBOARD_FAB2_LIB.BASEBOARD_FAB2(SCH_1):PAGE160
J 0
(-5290 5775);
DISPLAY 0.638298 (-5290 5775);
PAINT PINK (-5290 5775);
DISPLAY INVISIBLE (-5290 5775);
FORCEADD DESIGN_NOTE..1
(-1900 1175);
FORCEPROP 0 LAST L1 REMOVE 0 OHM RESISTOR  AND STUFF PULL-UP RES ON VR SMBUS IN MASS PRODUCTION
J 0
(-2100 1050);
DISPLAY 0.617021 (-2100 1050);
PAINT WHITE (-2100 1050);
FORCEPROP 2 LAST CDS_LIB mstr_symbols
J 0
(-1900 1175);
PAINT WHITE (-1900 1175);
DISPLAY INVISIBLE (-1900 1175);
FORCEPROP 1 LAST COMMENT_BODY TRUE
J 0
(-1875 1275);
DISPLAY 1.319149 (-1875 1275);
PAINT WHITE (-1875 1275);
DISPLAY INVISIBLE (-1875 1275);
WIRE 16 -1 (-3650 5225)(-3650 5075);
WIRE 16 -1 (-4000 5225)(-4000 5075);
WIRE 16 -1 (-4650 4600)(-4000 4600);
FORCEPROP 2 LAST SIG_NAME SMB_SLOTX24_STBY_LVC3_SDA_R
J 0
(-4660 4610);
DISPLAY 0.617021 (-4660 4610);
PAINT ORANGE (-4660 4610);
WIRE 16 -1 (-4000 4875)(-4000 4600);
WIRE 16 -1 (-4000 4600)(-3450 4600);
WIRE 16 -1 (-4600 3700)(-3450 3700);
FORCEPROP 2 LAST SIG_NAME SMB_LAN_STBY_LVC3_SDA_R
J 0
(-4610 3710);
DISPLAY 0.617021 (-4610 3710);
PAINT ORANGE (-4610 3710);
WIRE 16 -1 (-3650 4875)(-3650 4425);
WIRE 16 -1 (-3650 4425)(-3450 4425);
WIRE 16 -1 (-4650 4425)(-3650 4425);
FORCEPROP 2 LAST SIG_NAME SMB_SLOTX24_STBY_LVC3_SCL_R
J 0
(-4635 4435);
DISPLAY 0.617021 (-4635 4435);
PAINT ORANGE (-4635 4435);
WIRE 16 -1 (-3250 4600)(-2225 4600);
FORCEPROP 0 LAST SIG_NAME SMB_SLOTX24_BMC_STBY_LVC3_SDA
J 2
(-2200 4610);
DISPLAY 0.617021 (-2200 4610);
PAINT ORANGE (-2200 4610);
WIRE 16 -1 (-3250 4425)(-2225 4425);
FORCEPROP 0 LAST SIG_NAME SMB_SLOTX24_BMC_STBY_LVC3_SCL
J 2
(-2200 4435);
DISPLAY 0.617021 (-2200 4435);
PAINT ORANGE (-2200 4435);
WIRE 16 -1 (-4625 3525)(-3450 3525);
FORCEPROP 2 LAST SIG_NAME SMB_LAN_STBY_LVC3_SCL_R
J 0
(-4610 3535);
DISPLAY 0.617021 (-4610 3535);
PAINT ORANGE (-4610 3535);
WIRE 16 -1 (-3250 3525)(-2225 3525);
FORCEPROP 0 LAST SIG_NAME SMB_LAN_STBY_LVC3_SCL
J 2
(-2200 3535);
DISPLAY 0.617021 (-2200 3535);
PAINT ORANGE (-2200 3535);
WIRE 16 -1 (-3250 3700)(-2225 3700);
FORCEPROP 0 LAST SIG_NAME SMB_LAN_STBY_LVC3_SDA
J 2
(-2200 3710);
DISPLAY 0.617021 (-2200 3710);
PAINT ORANGE (-2200 3710);
WIRE 16 2175 (-4225 3150)(-4225 5400);
WIRE 16 2175 (-3025 3150)(-4225 3150);
WIRE 16 2175 (-4225 5400)(-3025 5400);
WIRE 16 2175 (-3025 5400)(-3025 3150);
DOT 1 (-3650 4425);
DOT 1 (-4000 4600);
QUIT
